# S9S_MB_2U (Grand Teton) — schematic netlist excerpt (pin names and nets, part order shuffled) for the footprints in the layout excerpt that follows; sources: Cadence DE-HDL packaged netlist, KiCad conversion of 03242023_DA0F0TMBIJ0_F0T_Motherboard_J_brd_V01_OCP.brd

Q37  MOSFET_NCH_DUAL  PJT138K IC  pkg SOT363XD  page 260
  S1  = GND
  G1  = VR_P5V_EN
  D2  = VR_P5V_EN_D_R1
  S2  = GND
  G2  = VR_P5V_EN_N
  D1  = VR_P5V_EN_N

R3482  Q_RES  33.2 1% CHIP  pkg 0402LF  page 213 : A = GPU_FPGA_BOOT_EN ; B = GPU_FPGA_BOOT_EN_R

(kicad_pcb
	(version 20260206)
	(generator "pcbnew")
	(generator_version "10.0")
	(general
		(thickness 1.6)
		(legacy_teardrops no)
	)
	(paper "A4")
	(title_block
		(title "03242023_DA0F0TMBIJ0_F0T_Motherboard_J_brd_V01_OCP.brd")
		(comment 1 "Grand Teton / footprints 1774-1775 of 6105")
	)
	(layers
		(0 "F.Cu" signal "TOP")
		(4 "In1.Cu" signal "GND")
		(6 "In2.Cu" signal "IN1")
		(8 "In3.Cu" signal "GND1")
		(10 "In4.Cu" signal "IN2")
		(12 "In5.Cu" signal "GND2")
		(14 "In6.Cu" signal "IN3")
		(16 "In7.Cu" signal "GND3")
		(18 "In8.Cu" signal "VCC")
		(20 "In9.Cu" signal "VCC1")
		(22 "In10.Cu" signal "GND4")
		(24 "In11.Cu" signal "IN4")
		(26 "In12.Cu" signal "GND5")
		(28 "In13.Cu" signal "IN5")
		(30 "In14.Cu" signal "GND6")
		(32 "In15.Cu" signal "IN6")
		(34 "In16.Cu" signal "GND7")
		(2 "B.Cu" signal "BOTTOM")
		(9 "F.Adhes" user "F.Adhesive")
		(11 "B.Adhes" user "B.Adhesive")
		(13 "F.Paste" user "Package Geometry/Pastemask Top")
		(15 "B.Paste" user "Package Geometry/Pastemask Bottom")
		(5 "F.SilkS" user "Ref Des/Silkscreen Top")
		(7 "B.SilkS" user "Ref Des/Silkscreen Bottom")
		(1 "F.Mask" user "Board Geometry/Soldermask Top")
		(3 "B.Mask" user "Board Geometry/Soldermask Bottom")
		(17 "Dwgs.User" user "User.Drawings")
		(19 "Cmts.User" user "User.Comments")
		(21 "Eco1.User" user "User.Eco1")
		(23 "Eco2.User" user "User.Eco2")
		(25 "Edge.Cuts" user "Board Geometry/Outline")
		(27 "Margin" user)
		(31 "F.CrtYd" user "Package Geometry/Place Bound Top")
		(29 "B.CrtYd" user "Package Geometry/Place Bound Bottom")
		(35 "F.Fab" user "Ref Des/Assembly Top")
		(33 "B.Fab" user "Ref Des/Assembly Bottom")
	)
	(footprint ""
		(layer "F.Cu")
		(at 166.196772 -129.036318 -90)
		(property "Reference" "Q37"
			(at 2.027428 -1.224788 0)
			(unlocked yes)
			(layer "F.SilkS")
			(effects
				(font
					(size 0.7874 0.5842)
					(thickness 0.1524)
				)
				(justify left)
			)
		)
		(property "Value" ""
			(at 0 0 270)
			(layer "F.Fab")
			(effects
				(font
					(size 1.27 1.27)
				)
			)
		)
		(duplicate_pad_numbers_are_jumpers no)
		(fp_line
			(start -1.332738 1.100074)
			(end -1.332738 -1.100074)
			(stroke
				(width 0.1524)
				(type default)
			)
			(layer "F.SilkS")
		)
		(fp_line
			(start 1.332738 1.100074)
			(end -1.332738 1.100074)
			(stroke
				(width 0.1524)
				(type default)
			)
			(layer "F.SilkS")
		)
		(fp_line
			(start 0 -0.541274)
			(end 0.4826 -1.100074)
			(stroke
				(width 0.1524)
				(type default)
			)
			(layer "F.SilkS")
		)
		(fp_line
			(start -1.332738 -1.100074)
			(end -0.4826 -1.100074)
			(stroke
				(width 0.1524)
				(type default)
			)
			(layer "F.SilkS")
		)
		(fp_line
			(start -0.4826 -1.100074)
			(end 0 -0.541274)
			(stroke
				(width 0.1524)
				(type default)
			)
			(layer "F.SilkS")
		)
		(fp_line
			(start 0.4826 -1.100074)
			(end 1.332738 -1.100074)
			(stroke
				(width 0.1524)
				(type default)
			)
			(layer "F.SilkS")
		)
		(fp_line
			(start 1.332738 -1.100074)
			(end 1.332738 1.100074)
			(stroke
				(width 0.1524)
				(type default)
			)
			(layer "F.SilkS")
		)
		(fp_poly
			(pts
				(xy -1.53416 -1.988312) (xy -1.323086 -1.232408) (xy -2.054606 -1.517142)
			)
			(stroke
				(width 0)
				(type default)
			)
			(fill yes)
			(layer "F.SilkS")
		)
		(fp_line
			(start -0.674878 1.100074)
			(end -0.674878 -1.100074)
			(stroke
				(width 0.1)
				(type default)
			)
			(layer "F.Fab")
		)
		(fp_line
			(start 0.674878 1.100074)
			(end -0.674878 1.100074)
			(stroke
				(width 0.1)
				(type default)
			)
			(layer "F.Fab")
		)
		(fp_line
			(start -0.674878 -1.100074)
			(end 0.674878 -1.100074)
			(stroke
				(width 0.1)
				(type default)
			)
			(layer "F.Fab")
		)
		(fp_line
			(start 0.674878 -1.100074)
			(end 0.674878 1.100074)
			(stroke
				(width 0.1)
				(type default)
			)
			(layer "F.Fab")
		)
		(fp_poly
			(pts
				(xy -2.2352 -0.298958) (xy -2.2352 -1.001014) (xy -1.533144 -0.649986)
			)
			(stroke
				(width 0)
				(type default)
			)
			(fill yes)
			(layer "F.Fab")
		)
		(pad "1" smd rect
			(at -0.94996 -0.649986)
			(size 0.4318 0.508)
			(layers "F.Cu" "F.Mask" "F.Paste")
			(net "GND")
		)
		(pad "2" smd rect
			(at -0.94996 0)
			(size 0.4318 0.508)
			(layers "F.Cu" "F.Mask" "F.Paste")
			(net "VR_P5V_EN")
		)
		(pad "3" smd rect
			(at -0.94996 0.649986)
			(size 0.4318 0.508)
			(layers "F.Cu" "F.Mask" "F.Paste")
			(net "VR_P5V_EN_D_R1")
		)
		(pad "4" smd rect
			(at 0.94996 0.649986)
			(size 0.4318 0.508)
			(layers "F.Cu" "F.Mask" "F.Paste")
			(net "GND")
		)
		(pad "5" smd rect
			(at 0.94996 0)
			(size 0.4318 0.508)
			(layers "F.Cu" "F.Mask" "F.Paste")
			(net "VR_P5V_EN_N")
		)
		(pad "6" smd rect
			(at 0.94996 -0.649986)
			(size 0.4318 0.508)
			(layers "F.Cu" "F.Mask" "F.Paste")
			(net "VR_P5V_EN_N")
		)
	)
	(footprint ""
		(layer "F.Cu")
		(at 157.02788 -116.296948)
		(property "Reference" "R3482"
			(at 0 0 0)
			(layer "F.SilkS")
			(hide yes)
			(effects
				(font
					(size 1.27 1.27)
				)
			)
		)
		(property "Value" ""
			(at 0 0 0)
			(layer "F.Fab")
			(effects
				(font
					(size 1.27 1.27)
				)
			)
		)
		(duplicate_pad_numbers_are_jumpers no)
		(fp_line
			(start -0.7874 -0.4064)
			(end 0.7874 -0.4064)
			(stroke
				(width 0.1524)
				(type default)
			)
			(layer "F.SilkS")
		)
		(fp_line
			(start -0.7874 0.4064)
			(end -0.7874 -0.4064)
			(stroke
				(width 0.1524)
				(type default)
			)
			(layer "F.SilkS")
		)
		(fp_line
			(start 0.7874 -0.4064)
			(end 0.7874 0.4064)
			(stroke
				(width 0.1524)
				(type default)
			)
			(layer "F.SilkS")
		)
		(fp_line
			(start 0.7874 0.4064)
			(end -0.7874 0.4064)
			(stroke
				(width 0.1524)
				(type default)
			)
			(layer "F.SilkS")
		)
		(fp_line
			(start -0.67945 -0.305054)
			(end -0.12065 -0.305054)
			(stroke
				(width 0.1)
				(type default)
			)
			(layer "F.Fab")
		)
		(fp_line
			(start -0.67945 0.3048)
			(end -0.67945 -0.305054)
			(stroke
				(width 0.1)
				(type default)
			)
			(layer "F.Fab")
		)
		(fp_line
			(start -0.12065 -0.305054)
			(end -0.12065 -0.2794)
			(stroke
				(width 0.1)
				(type default)
			)
			(layer "F.Fab")
		)
		(fp_line
			(start -0.12065 -0.2794)
			(end 0.12065 -0.2794)
			(stroke
				(width 0.1)
				(type default)
			)
			(layer "F.Fab")
		)
		(fp_line
			(start -0.12065 0.2794)
			(end -0.12065 0.3048)
			(stroke
				(width 0.1)
				(type default)
			)
			(layer "F.Fab")
		)
		(fp_line
			(start -0.12065 0.3048)
			(end -0.67945 0.3048)
			(stroke
				(width 0.1)
				(type default)
			)
			(layer "F.Fab")
		)
		(fp_line
			(start 0.120396 0.2794)
			(end -0.12065 0.2794)
			(stroke
				(width 0.1)
				(type default)
			)
			(layer "F.Fab")
		)
		(fp_line
			(start 0.120396 0.3048)
			(end 0.120396 0.2794)
			(stroke
				(width 0.1)
				(type default)
			)
			(layer "F.Fab")
		)
		(fp_line
			(start 0.12065 -0.3048)
			(end 0.67945 -0.3048)
			(stroke
				(width 0.1)
				(type default)
			)
			(layer "F.Fab")
		)
		(fp_line
			(start 0.12065 -0.2794)
			(end 0.12065 -0.3048)
			(stroke
				(width 0.1)
				(type default)
			)
			(layer "F.Fab")
		)
		(fp_line
			(start 0.67945 -0.3048)
			(end 0.67945 0.3048)
			(stroke
				(width 0.1)
				(type default)
			)
			(layer "F.Fab")
		)
		(fp_line
			(start 0.67945 0.3048)
			(end 0.120396 0.3048)
			(stroke
				(width 0.1)
				(type default)
			)
			(layer "F.Fab")
		)
		(pad "1" smd circle
			(at -0.40005 0)
			(size 0 0)
			(layers "F.Cu" "F.Mask" "F.Paste")
			(net "GPU_FPGA_BOOT_EN")
		)
		(pad "2" smd circle
			(at 0.40005 0)
			(size 0 0)
			(layers "F.Cu" "F.Mask" "F.Paste")
			(net "GPU_FPGA_BOOT_EN_R")
		)
	)
)
